# SCM (Grand Teton) — schematic netlist excerpt (pin names and nets, part order shuffled) for the footprints in the layout excerpt that follows; sources: Cadence DE-HDL packaged netlist, KiCad conversion of 12092022_DA0F0TMDCD0_F0T_Management_Board_D_brd_V3_OCP.brd

R320  Q_RES  0 5% CHIP  pkg 0402LF  page 35 : A = PWRGD_P2V5_AUX_R1 ; B = PWRGD_P2V5_AUX

Q5  MOSFET_NCH_4D1S  NTGS4141NT1G IC  pkg TSOP6XB  page 17
  \1\  = PGPPA_BMC_AUX_L
  \2\  = PGPPA_BMC_AUX_L
  \3\  = LPC_ESPI_SEL_N
  \4\  = P1V8_AUX
  \5\  = PGPPA_BMC_AUX_L
  \6\  = PGPPA_BMC_AUX_L

(kicad_pcb
	(version 20260206)
	(generator "pcbnew")
	(generator_version "10.0")
	(general
		(thickness 1.6)
		(legacy_teardrops no)
	)
	(paper "A4")
	(title_block
		(title "12092022_DA0F0TMDCD0_F0T_Management_Board_D_brd_V3_OCP.brd")
		(comment 1 "Grand Teton / footprints 1330-1331 of 1440")
	)
	(layers
		(0 "F.Cu" signal "TOP")
		(4 "In1.Cu" signal "GND")
		(6 "In2.Cu" signal "IN1")
		(8 "In3.Cu" signal "GND1")
		(10 "In4.Cu" signal "IN2")
		(12 "In5.Cu" signal "VCC")
		(14 "In6.Cu" signal "VCC1")
		(16 "In7.Cu" signal "IN3")
		(18 "In8.Cu" signal "GND2")
		(20 "In9.Cu" signal "IN4")
		(22 "In10.Cu" signal "GND3")
		(2 "B.Cu" signal "BOTTOM")
		(9 "F.Adhes" user "F.Adhesive")
		(11 "B.Adhes" user "B.Adhesive")
		(13 "F.Paste" user "Package Geometry/Pastemask Top")
		(15 "B.Paste" user "Package Geometry/Pastemask Bottom")
		(5 "F.SilkS" user "Ref Des/Silkscreen Top")
		(7 "B.SilkS" user "Ref Des/Silkscreen Bottom")
		(1 "F.Mask" user "Board Geometry/Soldermask Top")
		(3 "B.Mask" user "Board Geometry/Soldermask Bottom")
		(17 "Dwgs.User" user "User.Drawings")
		(19 "Cmts.User" user "User.Comments")
		(21 "Eco1.User" user "User.Eco1")
		(23 "Eco2.User" user "User.Eco2")
		(25 "Edge.Cuts" user "Board Geometry/Outline")
		(27 "Margin" user)
		(31 "F.CrtYd" user "Package Geometry/Place Bound Top")
		(29 "B.CrtYd" user "Package Geometry/Place Bound Bottom")
		(35 "F.Fab" user "Ref Des/Assembly Top")
		(33 "B.Fab" user "Ref Des/Assembly Bottom")
	)
	(footprint ""
		(layer "B.Cu")
		(at 66.1035 -94.8182 90)
		(property "Reference" "Q5"
			(at 2.29743 -1.7907 0)
			(unlocked yes)
			(layer "B.SilkS")
			(effects
				(font
					(size 0.7874 0.5842)
					(thickness 0.1524)
				)
				(justify left mirror)
			)
		)
		(property "Value" ""
			(at 0 0 90)
			(layer "B.Fab")
			(effects
				(font
					(size 1.27 1.27)
				)
				(justify mirror)
			)
		)
		(duplicate_pad_numbers_are_jumpers no)
		(fp_line
			(start 1.834896 -1.550162)
			(end 1.834896 1.550162)
			(stroke
				(width 0.1524)
				(type default)
			)
			(layer "B.SilkS")
		)
		(fp_line
			(start 0.494538 -1.550162)
			(end 1.834896 -1.550162)
			(stroke
				(width 0.1524)
				(type default)
			)
			(layer "B.SilkS")
		)
		(fp_line
			(start -0.494538 -1.550162)
			(end 0 -0.94996)
			(stroke
				(width 0.1524)
				(type default)
			)
			(layer "B.SilkS")
		)
		(fp_line
			(start -1.834896 -1.550162)
			(end -0.494538 -1.550162)
			(stroke
				(width 0.1524)
				(type default)
			)
			(layer "B.SilkS")
		)
		(fp_line
			(start 0 -0.94996)
			(end 0.494538 -1.550162)
			(stroke
				(width 0.1524)
				(type default)
			)
			(layer "B.SilkS")
		)
		(fp_line
			(start 1.834896 1.550162)
			(end -1.834896 1.550162)
			(stroke
				(width 0.1524)
				(type default)
			)
			(layer "B.SilkS")
		)
		(fp_line
			(start -1.834896 1.550162)
			(end -1.834896 -1.550162)
			(stroke
				(width 0.1524)
				(type default)
			)
			(layer "B.SilkS")
		)
		(fp_poly
			(pts
				(xy 1.1938 -1.7145) (xy 0.6858 -2.7305) (xy 1.7018 -2.7305)
			)
			(stroke
				(width 0)
				(type default)
			)
			(fill yes)
			(layer "B.SilkS")
		)
		(fp_line
			(start 0.850138 -1.550162)
			(end -0.850138 -1.550162)
			(stroke
				(width 0.1)
				(type default)
			)
			(layer "B.Fab")
		)
		(fp_line
			(start -0.850138 -1.550162)
			(end -0.850138 1.550162)
			(stroke
				(width 0.1)
				(type default)
			)
			(layer "B.Fab")
		)
		(fp_line
			(start 0.850138 1.550162)
			(end 0.850138 -1.550162)
			(stroke
				(width 0.1)
				(type default)
			)
			(layer "B.Fab")
		)
		(fp_line
			(start -0.850138 1.550162)
			(end 0.850138 1.550162)
			(stroke
				(width 0.1)
				(type default)
			)
			(layer "B.Fab")
		)
		(fp_poly
			(pts
				(xy 2.081784 -0.94996) (xy 3.097784 -1.45796) (xy 3.097784 -0.44196)
			)
			(stroke
				(width 0)
				(type default)
			)
			(fill yes)
			(layer "B.Fab")
		)
		(pad "1" smd rect
			(at 1.199896 -0.94996 180)
			(size 0.7112 1.016)
			(layers "B.Cu" "B.Mask" "B.Paste")
			(net "PGPPA_BMC_AUX_L")
		)
		(pad "2" smd rect
			(at 1.199896 0 180)
			(size 0.7112 1.016)
			(layers "B.Cu" "B.Mask" "B.Paste")
			(net "PGPPA_BMC_AUX_L")
		)
		(pad "3" smd rect
			(at 1.199896 0.94996 180)
			(size 0.7112 1.016)
			(layers "B.Cu" "B.Mask" "B.Paste")
			(net "LPC_ESPI_SEL_N")
		)
		(pad "4" smd rect
			(at -1.199896 0.94996 180)
			(size 0.7112 1.016)
			(layers "B.Cu" "B.Mask" "B.Paste")
			(net "P1V8_AUX")
		)
		(pad "5" smd rect
			(at -1.199896 0 180)
			(size 0.7112 1.016)
			(layers "B.Cu" "B.Mask" "B.Paste")
			(net "PGPPA_BMC_AUX_L")
		)
		(pad "6" smd rect
			(at -1.199896 -0.94996 180)
			(size 0.7112 1.016)
			(layers "B.Cu" "B.Mask" "B.Paste")
			(net "PGPPA_BMC_AUX_L")
		)
	)
	(footprint ""
		(layer "B.Cu")
		(at 12.319 -98.552)
		(property "Reference" "R320"
			(at 0 0 0)
			(layer "B.SilkS")
			(hide yes)
			(effects
				(font
					(size 1.27 1.27)
				)
				(justify mirror)
			)
		)
		(property "Value" ""
			(at 0 0 0)
			(layer "B.Fab")
			(effects
				(font
					(size 1.27 1.27)
				)
				(justify mirror)
			)
		)
		(duplicate_pad_numbers_are_jumpers no)
		(fp_line
			(start -0.7874 -0.4064)
			(end -0.7874 0.4064)
			(stroke
				(width 0.1524)
				(type default)
			)
			(layer "B.SilkS")
		)
		(fp_line
			(start -0.7874 0.4064)
			(end 0.7874 0.4064)
			(stroke
				(width 0.1524)
				(type default)
			)
			(layer "B.SilkS")
		)
		(fp_line
			(start 0.7874 -0.4064)
			(end -0.7874 -0.4064)
			(stroke
				(width 0.1524)
				(type default)
			)
			(layer "B.SilkS")
		)
		(fp_line
			(start 0.7874 0.4064)
			(end 0.7874 -0.4064)
			(stroke
				(width 0.1524)
				(type default)
			)
			(layer "B.SilkS")
		)
		(fp_line
			(start -0.67945 -0.3048)
			(end -0.67945 0.3048)
			(stroke
				(width 0.1)
				(type default)
			)
			(layer "B.Fab")
		)
		(fp_line
			(start -0.67945 0.3048)
			(end -0.120396 0.3048)
			(stroke
				(width 0.1)
				(type default)
			)
			(layer "B.Fab")
		)
		(fp_line
			(start -0.12065 -0.3048)
			(end -0.67945 -0.3048)
			(stroke
				(width 0.1)
				(type default)
			)
			(layer "B.Fab")
		)
		(fp_line
			(start -0.12065 -0.2794)
			(end -0.12065 -0.3048)
			(stroke
				(width 0.1)
				(type default)
			)
			(layer "B.Fab")
		)
		(fp_line
			(start -0.120396 0.2794)
			(end 0.12065 0.2794)
			(stroke
				(width 0.1)
				(type default)
			)
			(layer "B.Fab")
		)
		(fp_line
			(start -0.120396 0.3048)
			(end -0.120396 0.2794)
			(stroke
				(width 0.1)
				(type default)
			)
			(layer "B.Fab")
		)
		(fp_line
			(start 0.12065 -0.305054)
			(end 0.12065 -0.2794)
			(stroke
				(width 0.1)
				(type default)
			)
			(layer "B.Fab")
		)
		(fp_line
			(start 0.12065 -0.2794)
			(end -0.12065 -0.2794)
			(stroke
				(width 0.1)
				(type default)
			)
			(layer "B.Fab")
		)
		(fp_line
			(start 0.12065 0.2794)
			(end 0.12065 0.3048)
			(stroke
				(width 0.1)
				(type default)
			)
			(layer "B.Fab")
		)
		(fp_line
			(start 0.12065 0.3048)
			(end 0.67945 0.3048)
			(stroke
				(width 0.1)
				(type default)
			)
			(layer "B.Fab")
		)
		(fp_line
			(start 0.67945 -0.305054)
			(end 0.12065 -0.305054)
			(stroke
				(width 0.1)
				(type default)
			)
			(layer "B.Fab")
		)
		(fp_line
			(start 0.67945 0.3048)
			(end 0.67945 -0.305054)
			(stroke
				(width 0.1)
				(type default)
			)
			(layer "B.Fab")
		)
		(pad "1" smd circle
			(at 0.40005 0 180)
			(size 0 0)
			(layers "B.Cu" "B.Mask" "B.Paste")
			(net "PWRGD_P2V5_AUX_R1")
		)
		(pad "2" smd circle
			(at -0.40005 0 180)
			(size 0 0)
			(layers "B.Cu" "B.Mask" "B.Paste")
			(net "PWRGD_P2V5_AUX")
		)
	)
)
